(kicad_pcb
	(version 20260206)
	(generator "pcbnew")
	(generator_version "10.0")
	(general
		(thickness 1.6)
		(legacy_teardrops no)
	)
	(paper "A4")
	(title_block
		(title "baseboard — 13948-1b.1110WZS1818.brd")
		(comment 1 "Honey Badger (Wiwynn) / footprints 2416-2423 of 2523")
	)
	(layers
		(0 "F.Cu" signal "TOP")
		(4 "In1.Cu" signal "L2GND")
		(6 "In2.Cu" signal "L3")
		(8 "In3.Cu" signal "L4VCC")
		(10 "In4.Cu" signal "L5VCC")
		(12 "In5.Cu" signal "L6")
		(14 "In6.Cu" signal "L7GND")
		(2 "B.Cu" signal "BOTTOM")
		(9 "F.Adhes" user "F.Adhesive")
		(11 "B.Adhes" user "B.Adhesive")
		(13 "F.Paste" user "Package Geometry/Pastemask Top")
		(15 "B.Paste" user "Package Geometry/Pastemask Bottom")
		(5 "F.SilkS" user "Ref Des/Silkscreen Top")
		(7 "B.SilkS" user "Ref Des/Silkscreen Bottom")
		(1 "F.Mask" user "Board Geometry/Soldermask Top")
		(3 "B.Mask" user "Board Geometry/Soldermask Bottom")
		(17 "Dwgs.User" user "User.Drawings")
		(19 "Cmts.User" user "User.Comments")
		(21 "Eco1.User" user "User.Eco1")
		(23 "Eco2.User" user "User.Eco2")
		(25 "Edge.Cuts" user "Board Geometry/Outline")
		(27 "Margin" user)
		(31 "F.CrtYd" user "Package Geometry/Place Bound Top")
		(29 "B.CrtYd" user "Package Geometry/Place Bound Bottom")
		(35 "F.Fab" user "Ref Des/Assembly Top")
		(33 "B.Fab" user "Ref Des/Assembly Bottom")
	)
	(footprint ""
		(layer "B.Cu")
		(at 186.744864 -28.266136 180)
		(property "Reference" "C228"
			(at 0 0 0)
			(layer "B.SilkS")
			(hide yes)
			(effects
				(font
					(size 1.27 1.27)
				)
				(justify mirror)
			)
		)
		(property "Value" "SCD1U16V2KX-3GP"
			(at -1.1811 -2.7051 180)
			(unlocked yes)
			(layer "B.Fab")
			(hide yes)
			(effects
				(font
					(size 1.016 1.016)
					(thickness 0.1524)
				)
				(justify mirror)
			)
		)
		(property "Device Type" "C402H22"
			(at -1.1811 -4.2291 180)
			(unlocked yes)
			(layer "B.Fab")
			(hide yes)
			(effects
				(font
					(size 1.016 1.016)
					(thickness 0.1524)
				)
				(justify mirror)
			)
		)
		(duplicate_pad_numbers_are_jumpers no)
		(fp_rect
			(start 0.4318 0.9525)
			(end -0.4318 -0.9525)
			(stroke
				(width 0)
				(type default)
			)
			(fill no)
			(layer "B.CrtYd")
		)
		(fp_rect
			(start 0.4318 0.9525)
			(end -0.4318 -0.9525)
			(stroke
				(width 0)
				(type default)
			)
			(fill no)
			(layer "B.Fab")
		)
		(pad "1" smd custom
			(at 0 -0.4445)
			(size 0.1524 0.1524)
			(layers "B.Cu" "B.Mask" "B.Paste")
			(net "P3V3_STBY")
			(options
				(clearance outline)
				(anchor circle)
			)
			(primitives
				(gr_poly
					(pts
						(arc
							(start 0.3048 0.2032)
							(mid 0.275042 0.275042)
							(end 0.2032 0.3048)
						)
						(arc
							(start -0.2032 0.3048)
							(mid -0.275042 0.275042)
							(end -0.3048 0.2032)
						)
						(arc
							(start -0.3048 -0.2032)
							(mid -0.275042 -0.275042)
							(end -0.2032 -0.3048)
						)
						(arc
							(start 0.2032 -0.3048)
							(mid 0.275042 -0.275042)
							(end 0.3048 -0.2032)
						)
					)
					(width 0)
					(fill yes)
				)
			)
		)
		(pad "2" smd custom
			(at 0 0.4445)
			(size 0.1524 0.1524)
			(layers "B.Cu" "B.Mask" "B.Paste")
			(net "GND")
			(options
				(clearance outline)
				(anchor circle)
			)
			(primitives
				(gr_poly
					(pts
						(arc
							(start 0.3048 0.2032)
							(mid 0.275042 0.275042)
							(end 0.2032 0.3048)
						)
						(arc
							(start -0.2032 0.3048)
							(mid -0.275042 0.275042)
							(end -0.3048 0.2032)
						)
						(arc
							(start -0.3048 -0.2032)
							(mid -0.275042 -0.275042)
							(end -0.2032 -0.3048)
						)
						(arc
							(start 0.2032 -0.3048)
							(mid 0.275042 -0.275042)
							(end 0.3048 -0.2032)
						)
					)
					(width 0)
					(fill yes)
				)
			)
		)
	)
	(footprint ""
		(layer "B.Cu")
		(at 48.20793 -78.412086)
		(property "Reference" "TP148"
			(at 0 0 0)
			(layer "B.SilkS")
			(hide yes)
			(effects
				(font
					(size 1.27 1.27)
				)
				(justify mirror)
			)
		)
		(property "Value" "TPAD32-GP"
			(at 0 -3.166364 0)
			(unlocked yes)
			(layer "B.Fab")
			(hide yes)
			(effects
				(font
					(size 1.016 1.016)
					(thickness 0.1524)
				)
				(justify mirror)
			)
		)
		(property "Device Type" "TPAD32"
			(at 0 -4.690618 0)
			(unlocked yes)
			(layer "B.Fab")
			(hide yes)
			(effects
				(font
					(size 1.016 1.016)
					(thickness 0.1524)
				)
				(justify mirror)
			)
		)
		(duplicate_pad_numbers_are_jumpers no)
		(fp_poly
			(pts
				(arc
					(start 0.4064 0)
					(mid -0.4064 0)
					(end 0.4064 0)
				)
			)
			(stroke
				(width 0)
				(type default)
			)
			(fill no)
			(layer "B.CrtYd")
		)
		(fp_poly
			(pts
				(arc
					(start 0.7112 0)
					(mid -0.7112 0)
					(end 0.7112 0)
				)
			)
			(stroke
				(width 0)
				(type default)
			)
			(fill no)
			(layer "B.Fab")
		)
		(pad "1" smd circle
			(at 0 0 180)
			(size 0.8128 0.8128)
			(layers "B.Cu" "B.Mask" "B.Paste")
			(net "INT_CONN_A_SB2")
		)
	)
	(footprint ""
		(layer "B.Cu")
		(at 290.068 -177.927 90)
		(property "Reference" "C207"
			(at 0 0 90)
			(layer "B.SilkS")
			(hide yes)
			(effects
				(font
					(size 1.27 1.27)
				)
				(justify mirror)
			)
		)
		(property "Value" "SC1U10V3KX-4GP-U"
			(at 0 -2.8194 90)
			(unlocked yes)
			(layer "B.Fab")
			(hide yes)
			(effects
				(font
					(size 1.016 1.016)
					(thickness 0.1524)
				)
				(justify mirror)
			)
		)
		(property "Device Type" "C603H36"
			(at 0 -4.3434 90)
			(unlocked yes)
			(layer "B.Fab")
			(hide yes)
			(effects
				(font
					(size 1.016 1.016)
					(thickness 0.1524)
				)
				(justify mirror)
			)
		)
		(duplicate_pad_numbers_are_jumpers no)
		(fp_line
			(start -0.508 0)
			(end 0.508 0)
			(stroke
				(width 0.2032)
				(type default)
			)
			(layer "B.SilkS")
		)
		(fp_rect
			(start 0.5842 1.3335)
			(end -0.5842 -1.3335)
			(stroke
				(width 0)
				(type default)
			)
			(fill no)
			(layer "B.CrtYd")
		)
		(fp_rect
			(start 0.5842 1.3335)
			(end -0.5842 -1.3335)
			(stroke
				(width 0)
				(type default)
			)
			(fill no)
			(layer "B.Fab")
		)
		(pad "1" smd custom
			(at 0 -0.762 270)
			(size 0.2159 0.2159)
			(layers "B.Cu" "B.Mask" "B.Paste")
			(net "P1V26_STBY")
			(options
				(clearance outline)
				(anchor circle)
			)
			(primitives
				(gr_poly
					(pts
						(arc
							(start -0.3302 0.4318)
							(mid -0.402042 0.402042)
							(end -0.4318 0.3302)
						)
						(arc
							(start -0.4318 -0.3302)
							(mid -0.402042 -0.402042)
							(end -0.3302 -0.4318)
						)
						(arc
							(start 0.3302 -0.4318)
							(mid 0.402042 -0.402042)
							(end 0.4318 -0.3302)
						)
						(arc
							(start 0.4318 0.3302)
							(mid 0.402042 0.402042)
							(end 0.3302 0.4318)
						)
					)
					(width 0)
					(fill yes)
				)
			)
		)
		(pad "2" smd custom
			(at 0 0.762 270)
			(size 0.2159 0.2159)
			(layers "B.Cu" "B.Mask" "B.Paste")
			(net "GND")
			(options
				(clearance outline)
				(anchor circle)
			)
			(primitives
				(gr_poly
					(pts
						(arc
							(start -0.3302 0.4318)
							(mid -0.402042 0.402042)
							(end -0.4318 0.3302)
						)
						(arc
							(start -0.4318 -0.3302)
							(mid -0.402042 -0.402042)
							(end -0.3302 -0.4318)
						)
						(arc
							(start 0.3302 -0.4318)
							(mid 0.402042 -0.402042)
							(end 0.4318 -0.3302)
						)
						(arc
							(start 0.4318 0.3302)
							(mid 0.402042 0.402042)
							(end 0.3302 0.4318)
						)
					)
					(width 0)
					(fill yes)
				)
			)
		)
	)
	(footprint ""
		(layer "B.Cu")
		(at 117.484906 -36.64458)
		(property "Reference" "STP54"
			(at 0 0 0)
			(layer "B.SilkS")
			(hide yes)
			(effects
				(font
					(size 1.27 1.27)
				)
				(justify mirror)
			)
		)
		(property "Value" "TPAD28"
			(at -0.0127 -1.8034 0)
			(unlocked yes)
			(layer "B.Fab")
			(hide yes)
			(effects
				(font
					(size 1.016 1.016)
					(thickness 0.1524)
				)
				(justify mirror)
			)
		)
		(property "Device Type" "TPAD28"
			(at -0.0127 -3.3274 0)
			(unlocked yes)
			(layer "B.Fab")
			(hide yes)
			(effects
				(font
					(size 1.016 1.016)
					(thickness 0.1524)
				)
				(justify mirror)
			)
		)
		(duplicate_pad_numbers_are_jumpers no)
		(fp_poly
			(pts
				(arc
					(start 0.3556 0)
					(mid -0.3556 0)
					(end 0.3556 0)
				)
			)
			(stroke
				(width 0)
				(type default)
			)
			(fill no)
			(layer "B.CrtYd")
		)
		(fp_poly
			(pts
				(arc
					(start 0.6096 0)
					(mid -0.6096 0)
					(end 0.6096 0)
				)
			)
			(stroke
				(width 0)
				(type default)
			)
			(fill no)
			(layer "B.Fab")
		)
		(pad "1" smd circle
			(at 0 0 180)
			(size 0.7112 0.7112)
			(layers "B.Cu" "B.Mask" "B.Paste")
			(net "SPARE4")
		)
	)
	(footprint ""
		(layer "B.Cu")
		(at 274.193 -174.625 90)
		(property "Reference" "R360"
			(at 0 0 90)
			(layer "B.SilkS")
			(hide yes)
			(effects
				(font
					(size 1.27 1.27)
				)
				(justify mirror)
			)
		)
		(property "Value" "3K3R2F-2-GP"
			(at -0.064008 -3.993896 90)
			(unlocked yes)
			(layer "B.Fab")
			(hide yes)
			(effects
				(font
					(size 1.016 1.016)
					(thickness 0.1524)
				)
				(justify mirror)
			)
		)
		(property "Device Type" "R402H16"
			(at -0.064008 -5.517896 90)
			(unlocked yes)
			(layer "B.Fab")
			(hide yes)
			(effects
				(font
					(size 1.016 1.016)
					(thickness 0.1524)
				)
				(justify mirror)
			)
		)
		(duplicate_pad_numbers_are_jumpers no)
		(fp_line
			(start 0.508 -0.9398)
			(end 0.508 0.9398)
			(stroke
				(width 0.1524)
				(type default)
			)
			(layer "B.SilkS")
		)
		(fp_line
			(start -0.508 -0.9398)
			(end 0.508 -0.9398)
			(stroke
				(width 0.1524)
				(type default)
			)
			(layer "B.SilkS")
		)
		(fp_rect
			(start 0.508 0.9398)
			(end -0.508 -0.9398)
			(stroke
				(width 0)
				(type default)
			)
			(fill no)
			(layer "B.CrtYd")
		)
		(fp_rect
			(start 0.508 0.9398)
			(end -0.508 -0.9398)
			(stroke
				(width 0)
				(type default)
			)
			(fill no)
			(layer "B.Fab")
		)
		(pad "1" smd custom
			(at 0 -0.4445 270)
			(size 0.1397 0.1397)
			(layers "B.Cu" "B.Mask" "B.Paste")
			(net "P3V3_STBY")
			(options
				(clearance outline)
				(anchor circle)
			)
			(primitives
				(gr_poly
					(pts
						(arc
							(start -0.1778 0.2794)
							(mid -0.249642 0.249642)
							(end -0.2794 0.1778)
						)
						(arc
							(start -0.2794 -0.1778)
							(mid -0.249642 -0.249642)
							(end -0.1778 -0.2794)
						)
						(arc
							(start 0.1778 -0.2794)
							(mid 0.249642 -0.249642)
							(end 0.2794 -0.1778)
						)
						(arc
							(start 0.2794 0.1778)
							(mid 0.249642 0.249642)
							(end 0.1778 0.2794)
						)
					)
					(width 0)
					(fill yes)
				)
			)
		)
		(pad "2" smd custom
			(at 0 0.4445 270)
			(size 0.1397 0.1397)
			(layers "B.Cu" "B.Mask" "B.Paste")
			(net "ROMA13")
			(options
				(clearance outline)
				(anchor circle)
			)
			(primitives
				(gr_poly
					(pts
						(arc
							(start -0.1778 0.2794)
							(mid -0.249642 0.249642)
							(end -0.2794 0.1778)
						)
						(arc
							(start -0.2794 -0.1778)
							(mid -0.249642 -0.249642)
							(end -0.1778 -0.2794)
						)
						(arc
							(start 0.1778 -0.2794)
							(mid 0.249642 -0.249642)
							(end 0.2794 -0.1778)
						)
						(arc
							(start 0.2794 0.1778)
							(mid 0.249642 0.249642)
							(end 0.1778 0.2794)
						)
					)
					(width 0)
					(fill yes)
				)
			)
		)
	)
	(footprint ""
		(layer "B.Cu")
		(at 90.659966 -55.245 180)
		(property "Reference" "SC977"
			(at 0 0 0)
			(layer "B.SilkS")
			(hide yes)
			(effects
				(font
					(size 1.27 1.27)
				)
				(justify mirror)
			)
		)
		(property "Value" "SCD1U16V2KX-3GP"
			(at -1.1811 -2.7051 180)
			(unlocked yes)
			(layer "B.Fab")
			(hide yes)
			(effects
				(font
					(size 1.016 1.016)
					(thickness 0.1524)
				)
				(justify mirror)
			)
		)
		(property "Device Type" "C402H22"
			(at -1.1811 -4.2291 180)
			(unlocked yes)
			(layer "B.Fab")
			(hide yes)
			(effects
				(font
					(size 1.016 1.016)
					(thickness 0.1524)
				)
				(justify mirror)
			)
		)
		(duplicate_pad_numbers_are_jumpers no)
		(fp_rect
			(start 0.4318 0.9525)
			(end -0.4318 -0.9525)
			(stroke
				(width 0)
				(type default)
			)
			(fill no)
			(layer "B.CrtYd")
		)
		(fp_rect
			(start 0.4318 0.9525)
			(end -0.4318 -0.9525)
			(stroke
				(width 0)
				(type default)
			)
			(fill no)
			(layer "B.Fab")
		)
		(pad "1" smd custom
			(at 0 -0.4445)
			(size 0.1524 0.1524)
			(layers "B.Cu" "B.Mask" "B.Paste")
			(net "P1V8_C")
			(options
				(clearance outline)
				(anchor circle)
			)
			(primitives
				(gr_poly
					(pts
						(arc
							(start 0.3048 0.2032)
							(mid 0.275042 0.275042)
							(end 0.2032 0.3048)
						)
						(arc
							(start -0.2032 0.3048)
							(mid -0.275042 0.275042)
							(end -0.3048 0.2032)
						)
						(arc
							(start -0.3048 -0.2032)
							(mid -0.275042 -0.275042)
							(end -0.2032 -0.3048)
						)
						(arc
							(start 0.2032 -0.3048)
							(mid 0.275042 -0.275042)
							(end 0.3048 -0.2032)
						)
					)
					(width 0)
					(fill yes)
				)
			)
		)
		(pad "2" smd custom
			(at 0 0.4445)
			(size 0.1524 0.1524)
			(layers "B.Cu" "B.Mask" "B.Paste")
			(net "GND")
			(options
				(clearance outline)
				(anchor circle)
			)
			(primitives
				(gr_poly
					(pts
						(arc
							(start 0.3048 0.2032)
							(mid 0.275042 0.275042)
							(end 0.2032 0.3048)
						)
						(arc
							(start -0.2032 0.3048)
							(mid -0.275042 0.275042)
							(end -0.3048 0.2032)
						)
						(arc
							(start -0.3048 -0.2032)
							(mid -0.275042 -0.275042)
							(end -0.2032 -0.3048)
						)
						(arc
							(start 0.2032 -0.3048)
							(mid 0.275042 -0.275042)
							(end 0.3048 -0.2032)
						)
					)
					(width 0)
					(fill yes)
				)
			)
		)
	)
	(footprint ""
		(layer "B.Cu")
		(at 318.008 -174.625 90)
		(property "Reference" "R468"
			(at 0 0 90)
			(layer "B.SilkS")
			(hide yes)
			(effects
				(font
					(size 1.27 1.27)
				)
				(justify mirror)
			)
		)
		(property "Value" "0R2J-2-GP"
			(at -0.064008 -3.993896 90)
			(unlocked yes)
			(layer "B.Fab")
			(hide yes)
			(effects
				(font
					(size 1.016 1.016)
					(thickness 0.1524)
				)
				(justify mirror)
			)
		)
		(property "Device Type" "R402H16"
			(at -0.064008 -5.517896 90)
			(unlocked yes)
			(layer "B.Fab")
			(hide yes)
			(effects
				(font
					(size 1.016 1.016)
					(thickness 0.1524)
				)
				(justify mirror)
			)
		)
		(duplicate_pad_numbers_are_jumpers no)
		(fp_line
			(start 0.508 -0.9398)
			(end 0.508 0.9398)
			(stroke
				(width 0.1524)
				(type default)
			)
			(layer "B.SilkS")
		)
		(fp_line
			(start -0.508 -0.9398)
			(end 0.508 -0.9398)
			(stroke
				(width 0.1524)
				(type default)
			)
			(layer "B.SilkS")
		)
		(fp_rect
			(start 0.508 0.9398)
			(end -0.508 -0.9398)
			(stroke
				(width 0)
				(type default)
			)
			(fill no)
			(layer "B.CrtYd")
		)
		(fp_rect
			(start 0.508 0.9398)
			(end -0.508 -0.9398)
			(stroke
				(width 0)
				(type default)
			)
			(fill no)
			(layer "B.Fab")
		)
		(pad "1" smd custom
			(at 0 -0.4445 270)
			(size 0.1397 0.1397)
			(layers "B.Cu" "B.Mask" "B.Paste")
			(net "BMC0_SMB14_CLK")
			(options
				(clearance outline)
				(anchor circle)
			)
			(primitives
				(gr_poly
					(pts
						(arc
							(start -0.1778 0.2794)
							(mid -0.249642 0.249642)
							(end -0.2794 0.1778)
						)
						(arc
							(start -0.2794 -0.1778)
							(mid -0.249642 -0.249642)
							(end -0.1778 -0.2794)
						)
						(arc
							(start 0.1778 -0.2794)
							(mid 0.249642 -0.249642)
							(end 0.2794 -0.1778)
						)
						(arc
							(start 0.2794 0.1778)
							(mid 0.249642 0.249642)
							(end 0.1778 0.2794)
						)
					)
					(width 0)
					(fill yes)
				)
			)
		)
		(pad "2" smd custom
			(at 0 0.4445 270)
			(size 0.1397 0.1397)
			(layers "B.Cu" "B.Mask" "B.Paste")
			(net "EXP_IOC_BMC_SCL_14")
			(options
				(clearance outline)
				(anchor circle)
			)
			(primitives
				(gr_poly
					(pts
						(arc
							(start -0.1778 0.2794)
							(mid -0.249642 0.249642)
							(end -0.2794 0.1778)
						)
						(arc
							(start -0.2794 -0.1778)
							(mid -0.249642 -0.249642)
							(end -0.1778 -0.2794)
						)
						(arc
							(start 0.1778 -0.2794)
							(mid 0.249642 -0.249642)
							(end 0.2794 -0.1778)
						)
						(arc
							(start 0.2794 0.1778)
							(mid 0.249642 0.249642)
							(end 0.1778 0.2794)
						)
					)
					(width 0)
					(fill yes)
				)
			)
		)
	)
	(footprint ""
		(layer "B.Cu")
		(at 120.02897 -102.616 -90)
		(property "Reference" "SC1185"
			(at 0 0 90)
			(layer "B.SilkS")
			(hide yes)
			(effects
				(font
					(size 1.27 1.27)
				)
				(justify mirror)
			)
		)
		(property "Value" "SCD1U6D3V1KX-GP"
			(at 2.8321 -1.7399 270)
			(unlocked yes)
			(layer "B.Fab")
			(hide yes)
			(effects
				(font
					(size 1.016 1.016)
					(thickness 0.1524)
				)
				(justify mirror)
			)
		)
		(property "Device Type" "C0201H13"
			(at 2.8321 -3.2639 270)
			(unlocked yes)
			(layer "B.Fab")
			(hide yes)
			(effects
				(font
					(size 1.016 1.016)
					(thickness 0.1524)
				)
				(justify mirror)
			)
		)
		(duplicate_pad_numbers_are_jumpers no)
		(fp_rect
			(start 0.2794 0.6477)
			(end -0.2794 -0.6477)
			(stroke
				(width 0)
				(type default)
			)
			(fill no)
			(layer "B.CrtYd")
		)
		(fp_rect
			(start 0.2794 0.6477)
			(end -0.2794 -0.6477)
			(stroke
				(width 0)
				(type default)
			)
			(fill no)
			(layer "B.Fab")
		)
		(pad "1" smd custom
			(at 0 -0.2794 90)
			(size 0.0762 0.0762)
			(layers "B.Cu" "B.Mask" "B.Paste")
			(net "GB_VDDA")
			(options
				(clearance outline)
				(anchor circle)
			)
			(primitives
				(gr_poly
					(pts
						(arc
							(start 0.1524 0.127)
							(mid 0.137521 0.162921)
							(end 0.1016 0.1778)
						)
						(arc
							(start -0.1016 0.1778)
							(mid -0.137521 0.162921)
							(end -0.1524 0.127)
						)
						(arc
							(start -0.1524 -0.127)
							(mid -0.137521 -0.162921)
							(end -0.1016 -0.1778)
						)
						(arc
							(start 0.1016 -0.1778)
							(mid 0.137521 -0.162921)
							(end 0.1524 -0.127)
						)
					)
					(width 0)
					(fill yes)
				)
			)
		)
		(pad "2" smd custom
			(at 0 0.2794 90)
			(size 0.0762 0.0762)
			(layers "B.Cu" "B.Mask" "B.Paste")
			(net "GND")
			(options
				(clearance outline)
				(anchor circle)
			)
			(primitives
				(gr_poly
					(pts
						(arc
							(start 0.1524 0.127)
							(mid 0.137521 0.162921)
							(end 0.1016 0.1778)
						)
						(arc
							(start -0.1016 0.1778)
							(mid -0.137521 0.162921)
							(end -0.1524 0.127)
						)
						(arc
							(start -0.1524 -0.127)
							(mid -0.137521 -0.162921)
							(end -0.1016 -0.1778)
						)
						(arc
							(start 0.1016 -0.1778)
							(mid 0.137521 -0.162921)
							(end 0.1524 -0.127)
						)
					)
					(width 0)
					(fill yes)
				)
			)
		)
	)
)
